(kicad_pcb
	(version 20260206)
	(generator "pcbnew")
	(generator_version "10.0")
	(general
		(thickness 1.6)
		(legacy_teardrops no)
	)
	(paper "A4")
	(title_block
		(title "v1-chassis-manager — T6M_CM_d_v01_1031_1645.brd")
		(comment 1 "Open CloudServer (Microsoft) / footprints 1650-1659 of 2512")
	)
	(layers
		(0 "F.Cu" signal "TOP")
		(4 "In1.Cu" signal "GND1")
		(6 "In2.Cu" signal "IN1")
		(8 "In3.Cu" signal "VCC1")
		(10 "In4.Cu" signal "VCC2")
		(12 "In5.Cu" signal "GND2")
		(14 "In6.Cu" signal "IN2")
		(16 "In7.Cu" signal "IN3")
		(18 "In8.Cu" signal "GND3")
		(2 "B.Cu" signal "BOTTOM")
		(9 "F.Adhes" user "F.Adhesive")
		(11 "B.Adhes" user "B.Adhesive")
		(13 "F.Paste" user "Package Geometry/Pastemask Top")
		(15 "B.Paste" user "Package Geometry/Pastemask Bottom")
		(5 "F.SilkS" user "Ref Des/Silkscreen Top")
		(7 "B.SilkS" user "Ref Des/Silkscreen Bottom")
		(1 "F.Mask" user "Board Geometry/Soldermask Top")
		(3 "B.Mask" user "Board Geometry/Soldermask Bottom")
		(17 "Dwgs.User" user "User.Drawings")
		(19 "Cmts.User" user "User.Comments")
		(21 "Eco1.User" user "User.Eco1")
		(23 "Eco2.User" user "User.Eco2")
		(25 "Edge.Cuts" user "Board Geometry/Outline")
		(27 "Margin" user)
		(31 "F.CrtYd" user "Package Geometry/Place Bound Top")
		(29 "B.CrtYd" user "Package Geometry/Place Bound Bottom")
		(35 "F.Fab" user "Ref Des/Assembly Top")
		(33 "B.Fab" user "Ref Des/Assembly Bottom")
	)
	(footprint ""
		(layer "B.Cu")
		(at 133.4516 -46.9646 90)
		(property "Reference" "R1322"
			(at 3.0988 11.42873 270)
			(unlocked yes)
			(layer "B.SilkS")
			(effects
				(font
					(size 0.7874 0.5842)
					(thickness 0.1524)
				)
				(justify left mirror)
			)
		)
		(property "Value" ""
			(at 0 0 90)
			(layer "B.Fab")
			(effects
				(font
					(size 1.27 1.27)
				)
				(justify mirror)
			)
		)
		(duplicate_pad_numbers_are_jumpers no)
		(fp_line
			(start 0.7874 -0.4064)
			(end -0.7874 -0.4064)
			(stroke
				(width 0.1524)
				(type default)
			)
			(layer "B.SilkS")
		)
		(fp_line
			(start -0.7874 -0.4064)
			(end -0.7874 0.4064)
			(stroke
				(width 0.1524)
				(type default)
			)
			(layer "B.SilkS")
		)
		(fp_line
			(start 0.7874 0.4064)
			(end 0.7874 -0.4064)
			(stroke
				(width 0.1524)
				(type default)
			)
			(layer "B.SilkS")
		)
		(fp_line
			(start -0.7874 0.4064)
			(end 0.7874 0.4064)
			(stroke
				(width 0.1524)
				(type default)
			)
			(layer "B.SilkS")
		)
		(fp_poly
			(pts
				(xy 0.508 0.2794) (xy 0.508 0.2286) (xy 0.635 0.2286) (xy 0.635 -0.254) (xy 0.5334 -0.254) (xy 0.5334 -0.2794)
				(xy -0.5334 -0.2794) (xy -0.5334 -0.254) (xy -0.635 -0.254) (xy -0.635 0.254) (xy -0.5334 0.254)
				(xy -0.5334 0.2794)
			)
			(stroke
				(width 0)
				(type default)
			)
			(fill no)
			(layer "B.CrtYd")
		)
		(pad "1" smd rect
			(at -0.40005 0 270)
			(size 0.4572 0.508)
			(layers "B.Cu" "B.Mask" "B.Paste")
			(net "P5V_NODE1")
		)
		(pad "2" smd rect
			(at 0.40005 0 270)
			(size 0.4572 0.508)
			(layers "B.Cu" "B.Mask" "B.Paste")
			(net "UART_DCD_P4_N")
		)
	)
	(footprint ""
		(layer "B.Cu")
		(at 67.298062 -29.394658 -90)
		(property "Reference" "C142"
			(at -2.17805 0.141732 270)
			(unlocked yes)
			(layer "B.SilkS")
			(effects
				(font
					(size 0.7874 0.5842)
					(thickness 0.1524)
				)
				(justify left mirror)
			)
		)
		(property "Value" ""
			(at 0 0 90)
			(layer "B.Fab")
			(effects
				(font
					(size 1.27 1.27)
				)
				(justify mirror)
			)
		)
		(duplicate_pad_numbers_are_jumpers no)
		(fp_line
			(start -0.7874 0.4064)
			(end 0.7874 0.4064)
			(stroke
				(width 0.1524)
				(type default)
			)
			(layer "B.SilkS")
		)
		(fp_line
			(start 0.7874 0.4064)
			(end 0.7874 -0.4064)
			(stroke
				(width 0.1524)
				(type default)
			)
			(layer "B.SilkS")
		)
		(fp_line
			(start 0 0.381)
			(end 0 -0.381)
			(stroke
				(width 0.1524)
				(type default)
			)
			(layer "B.SilkS")
		)
		(fp_line
			(start -0.7874 -0.4064)
			(end -0.7874 0.4064)
			(stroke
				(width 0.1524)
				(type default)
			)
			(layer "B.SilkS")
		)
		(fp_line
			(start 0.7874 -0.4064)
			(end -0.7874 -0.4064)
			(stroke
				(width 0.1524)
				(type default)
			)
			(layer "B.SilkS")
		)
		(fp_poly
			(pts
				(xy 0.5334 0.254) (xy 0.635 0.254) (xy 0.635 0.2286) (xy 0.635 -0.254) (xy 0.5334 -0.254) (xy 0.5334 -0.2794)
				(xy -0.5334 -0.2794) (xy -0.5334 -0.254) (xy -0.635 -0.254) (xy -0.635 0.254) (xy -0.5334 0.254)
				(xy -0.5334 0.2794) (xy 0.508 0.2794) (xy 0.5334 0.2794)
			)
			(stroke
				(width 0)
				(type default)
			)
			(fill no)
			(layer "B.CrtYd")
		)
		(pad "1" smd rect
			(at -0.40005 0 90)
			(size 0.4572 0.508)
			(layers "B.Cu" "B.Mask" "B.Paste")
			(net "P1V5_NODE1_DDR3_VREF_A_A")
		)
		(pad "2" smd rect
			(at 0.40005 0 90)
			(size 0.4572 0.508)
			(layers "B.Cu" "B.Mask" "B.Paste")
			(net "GND")
		)
	)
	(footprint ""
		(layer "B.Cu")
		(at 100.696014 -171.758102)
		(property "Reference" "R778"
			(at 7.24916 0.977646 0)
			(unlocked yes)
			(layer "B.SilkS")
			(effects
				(font
					(size 0.7874 0.5842)
					(thickness 0.1524)
				)
				(justify left mirror)
			)
		)
		(property "Value" ""
			(at 0 0 0)
			(layer "B.Fab")
			(effects
				(font
					(size 1.27 1.27)
				)
				(justify mirror)
			)
		)
		(duplicate_pad_numbers_are_jumpers no)
		(fp_line
			(start -0.7874 -0.4064)
			(end -0.7874 0.4064)
			(stroke
				(width 0.1524)
				(type default)
			)
			(layer "B.SilkS")
		)
		(fp_line
			(start -0.7874 0.4064)
			(end 0.7874 0.4064)
			(stroke
				(width 0.1524)
				(type default)
			)
			(layer "B.SilkS")
		)
		(fp_line
			(start 0.7874 -0.4064)
			(end -0.7874 -0.4064)
			(stroke
				(width 0.1524)
				(type default)
			)
			(layer "B.SilkS")
		)
		(fp_line
			(start 0.7874 0.4064)
			(end 0.7874 -0.4064)
			(stroke
				(width 0.1524)
				(type default)
			)
			(layer "B.SilkS")
		)
		(fp_poly
			(pts
				(xy 0.508 0.2794) (xy 0.508 0.2286) (xy 0.635 0.2286) (xy 0.635 -0.254) (xy 0.5334 -0.254) (xy 0.5334 -0.2794)
				(xy -0.5334 -0.2794) (xy -0.5334 -0.254) (xy -0.635 -0.254) (xy -0.635 0.254) (xy -0.5334 0.254)
				(xy -0.5334 0.2794)
			)
			(stroke
				(width 0)
				(type default)
			)
			(fill no)
			(layer "B.CrtYd")
		)
		(pad "1" smd rect
			(at -0.40005 0 180)
			(size 0.4572 0.508)
			(layers "B.Cu" "B.Mask" "B.Paste")
			(net "P3V3_NODE1")
		)
		(pad "2" smd rect
			(at 0.40005 0 180)
			(size 0.4572 0.508)
			(layers "B.Cu" "B.Mask" "B.Paste")
			(net "FAN_PWM")
		)
	)
	(footprint ""
		(layer "B.Cu")
		(at 127.60706 -160.840166 180)
		(property "Reference" "U143"
			(at 1.017524 -3.659886 0)
			(unlocked yes)
			(layer "B.SilkS")
			(effects
				(font
					(size 0.7874 0.5842)
					(thickness 0.1524)
				)
				(justify mirror)
			)
		)
		(property "Value" ""
			(at 0 0 0)
			(layer "B.Fab")
			(effects
				(font
					(size 1.27 1.27)
				)
				(justify mirror)
			)
		)
		(duplicate_pad_numbers_are_jumpers no)
		(fp_line
			(start 1.651 1.905)
			(end 1.651 -1.905)
			(stroke
				(width 0.1524)
				(type default)
			)
			(layer "B.SilkS")
		)
		(fp_line
			(start 1.651 -1.905)
			(end -1.651 -1.905)
			(stroke
				(width 0.1524)
				(type default)
			)
			(layer "B.SilkS")
		)
		(fp_line
			(start -1.651 1.905)
			(end 1.651 1.905)
			(stroke
				(width 0.1524)
				(type default)
			)
			(layer "B.SilkS")
		)
		(fp_line
			(start -1.651 -1.905)
			(end -1.651 1.905)
			(stroke
				(width 0.1524)
				(type default)
			)
			(layer "B.SilkS")
		)
		(fp_poly
			(pts
				(xy 1.524 0.7112) (xy 1.524 1.7526) (xy 0.508 1.7526) (xy 0.508 0.6985) (xy -0.508 0.6985) (xy -0.508 1.7526)
				(xy -1.524 1.7526) (xy -1.524 0.6985) (xy -1.524 -0.6985) (xy -0.508 -0.6985) (xy -0.508 -1.7526)
				(xy 0.508 -1.7526) (xy 0.508 -0.6985) (xy 1.524 -0.6985) (xy 1.524 0.6985)
			)
			(stroke
				(width 0)
				(type default)
			)
			(fill no)
			(layer "B.CrtYd")
		)
		(fp_text user "G"
			(at 2.211832 1.385316 0)
			(unlocked yes)
			(layer "B.SilkS")
			(effects
				(font
					(size 0.635 0.4064)
					(thickness 0.1524)
				)
				(justify mirror)
			)
		)
		(fp_text user "D"
			(at -0.79756 -2.563622 0)
			(unlocked yes)
			(layer "B.SilkS")
			(effects
				(font
					(size 0.635 0.4064)
					(thickness 0.1524)
				)
				(justify mirror)
			)
		)
		(fp_text user "S"
			(at -2.055622 2.10185 0)
			(unlocked yes)
			(layer "B.SilkS")
			(effects
				(font
					(size 0.635 0.4064)
					(thickness 0.1524)
				)
				(justify mirror)
			)
		)
		(pad "D" smd rect
			(at 0 -1.1176)
			(size 1.016 1.27)
			(layers "B.Cu" "B.Mask" "B.Paste")
			(net "UART_RI_P6_N")
		)
		(pad "G" smd rect
			(at 1.016 1.1176)
			(size 1.016 1.27)
			(layers "B.Cu" "B.Mask" "B.Paste")
			(net "TACKOVER_EN")
		)
		(pad "S" smd rect
			(at -1.016 1.1176)
			(size 1.016 1.27)
			(layers "B.Cu" "B.Mask" "B.Paste")
			(net "UART_RI_P6_LS_N")
		)
	)
	(footprint ""
		(layer "B.Cu")
		(at 80.6831 -82.902044)
		(property "Reference" "R169"
			(at 3.9878 0.486156 0)
			(unlocked yes)
			(layer "B.SilkS")
			(effects
				(font
					(size 0.7874 0.5842)
					(thickness 0.1524)
				)
				(justify left mirror)
			)
		)
		(property "Value" ""
			(at 0 0 0)
			(layer "B.Fab")
			(effects
				(font
					(size 1.27 1.27)
				)
				(justify mirror)
			)
		)
		(duplicate_pad_numbers_are_jumpers no)
		(fp_line
			(start -0.7874 -0.4064)
			(end -0.7874 0.4064)
			(stroke
				(width 0.1524)
				(type default)
			)
			(layer "B.SilkS")
		)
		(fp_line
			(start -0.7874 0.4064)
			(end 0.7874 0.4064)
			(stroke
				(width 0.1524)
				(type default)
			)
			(layer "B.SilkS")
		)
		(fp_line
			(start 0.7874 -0.4064)
			(end -0.7874 -0.4064)
			(stroke
				(width 0.1524)
				(type default)
			)
			(layer "B.SilkS")
		)
		(fp_line
			(start 0.7874 0.4064)
			(end 0.7874 -0.4064)
			(stroke
				(width 0.1524)
				(type default)
			)
			(layer "B.SilkS")
		)
		(fp_poly
			(pts
				(xy 0.508 0.2794) (xy 0.508 0.2286) (xy 0.635 0.2286) (xy 0.635 -0.254) (xy 0.5334 -0.254) (xy 0.5334 -0.2794)
				(xy -0.5334 -0.2794) (xy -0.5334 -0.254) (xy -0.635 -0.254) (xy -0.635 0.254) (xy -0.5334 0.254)
				(xy -0.5334 0.2794)
			)
			(stroke
				(width 0)
				(type default)
			)
			(fill no)
			(layer "B.CrtYd")
		)
		(pad "1" smd rect
			(at -0.40005 0 180)
			(size 0.4572 0.508)
			(layers "B.Cu" "B.Mask" "B.Paste")
			(net "LPC_CPU_NODE1_CLK0_DS")
		)
		(pad "2" smd rect
			(at 0.40005 0 180)
			(size 0.4572 0.508)
			(layers "B.Cu" "B.Mask" "B.Paste")
			(net "P3V3_NODE1")
		)
	)
	(footprint ""
		(layer "B.Cu")
		(at 54.022498 -96.696784 -90)
		(property "Reference" "R81"
			(at -6.405118 4.421124 270)
			(unlocked yes)
			(layer "B.SilkS")
			(effects
				(font
					(size 0.7874 0.5842)
					(thickness 0.1524)
				)
				(justify left mirror)
			)
		)
		(property "Value" ""
			(at 0 0 90)
			(layer "B.Fab")
			(effects
				(font
					(size 1.27 1.27)
				)
				(justify mirror)
			)
		)
		(duplicate_pad_numbers_are_jumpers no)
		(fp_line
			(start -0.7874 0.4064)
			(end 0.7874 0.4064)
			(stroke
				(width 0.1524)
				(type default)
			)
			(layer "B.SilkS")
		)
		(fp_line
			(start 0.7874 0.4064)
			(end 0.7874 -0.4064)
			(stroke
				(width 0.1524)
				(type default)
			)
			(layer "B.SilkS")
		)
		(fp_line
			(start -0.7874 -0.4064)
			(end -0.7874 0.4064)
			(stroke
				(width 0.1524)
				(type default)
			)
			(layer "B.SilkS")
		)
		(fp_line
			(start 0.7874 -0.4064)
			(end -0.7874 -0.4064)
			(stroke
				(width 0.1524)
				(type default)
			)
			(layer "B.SilkS")
		)
		(fp_poly
			(pts
				(xy 0.508 0.2794) (xy 0.508 0.2286) (xy 0.635 0.2286) (xy 0.635 -0.254) (xy 0.5334 -0.254) (xy 0.5334 -0.2794)
				(xy -0.5334 -0.2794) (xy -0.5334 -0.254) (xy -0.635 -0.254) (xy -0.635 0.254) (xy -0.5334 0.254)
				(xy -0.5334 0.2794)
			)
			(stroke
				(width 0)
				(type default)
			)
			(fill no)
			(layer "B.CrtYd")
		)
		(pad "1" smd rect
			(at -0.40005 0 90)
			(size 0.4572 0.508)
			(layers "B.Cu" "B.Mask" "B.Paste")
			(net "GND")
		)
		(pad "2" smd rect
			(at 0.40005 0 90)
			(size 0.4572 0.508)
			(layers "B.Cu" "B.Mask" "B.Paste")
			(net "PD_CPU_NODE1_DFX_GPIO_GRP0_4")
		)
	)
	(footprint ""
		(layer "B.Cu")
		(at 135.196834 -41.439084 180)
		(property "Reference" "R1192"
			(at 5.415788 -19.031966 0)
			(unlocked yes)
			(layer "B.SilkS")
			(effects
				(font
					(size 0.7874 0.5842)
					(thickness 0.1524)
				)
				(justify left mirror)
			)
		)
		(property "Value" ""
			(at 0 0 0)
			(layer "B.Fab")
			(effects
				(font
					(size 1.27 1.27)
				)
				(justify mirror)
			)
		)
		(duplicate_pad_numbers_are_jumpers no)
		(fp_line
			(start 0.7874 0.4064)
			(end 0.7874 -0.4064)
			(stroke
				(width 0.1524)
				(type default)
			)
			(layer "B.SilkS")
		)
		(fp_line
			(start 0.7874 -0.4064)
			(end -0.7874 -0.4064)
			(stroke
				(width 0.1524)
				(type default)
			)
			(layer "B.SilkS")
		)
		(fp_line
			(start -0.7874 0.4064)
			(end 0.7874 0.4064)
			(stroke
				(width 0.1524)
				(type default)
			)
			(layer "B.SilkS")
		)
		(fp_line
			(start -0.7874 -0.4064)
			(end -0.7874 0.4064)
			(stroke
				(width 0.1524)
				(type default)
			)
			(layer "B.SilkS")
		)
		(fp_poly
			(pts
				(xy 0.508 0.2794) (xy 0.508 0.2286) (xy 0.635 0.2286) (xy 0.635 -0.254) (xy 0.5334 -0.254) (xy 0.5334 -0.2794)
				(xy -0.5334 -0.2794) (xy -0.5334 -0.254) (xy -0.635 -0.254) (xy -0.635 0.254) (xy -0.5334 0.254)
				(xy -0.5334 0.2794)
			)
			(stroke
				(width 0)
				(type default)
			)
			(fill no)
			(layer "B.CrtYd")
		)
		(pad "1" smd rect
			(at -0.40005 0)
			(size 0.4572 0.508)
			(layers "B.Cu" "B.Mask" "B.Paste")
			(net "SIO_JTAG_CPLD2_TCK")
		)
		(pad "2" smd rect
			(at 0.40005 0)
			(size 0.4572 0.508)
			(layers "B.Cu" "B.Mask" "B.Paste")
			(net "GND")
		)
	)
	(footprint ""
		(layer "B.Cu")
		(at 43.00982 -150.22449 90)
		(property "Reference" "C419"
			(at 7.986014 -11.738102 270)
			(unlocked yes)
			(layer "B.SilkS")
			(effects
				(font
					(size 0.7874 0.5842)
					(thickness 0.1524)
				)
				(justify left mirror)
			)
		)
		(property "Value" ""
			(at 0 0 90)
			(layer "B.Fab")
			(effects
				(font
					(size 1.27 1.27)
				)
				(justify mirror)
			)
		)
		(duplicate_pad_numbers_are_jumpers no)
		(fp_line
			(start 0.7874 -0.4064)
			(end -0.7874 -0.4064)
			(stroke
				(width 0.1524)
				(type default)
			)
			(layer "B.SilkS")
		)
		(fp_line
			(start -0.7874 -0.4064)
			(end -0.7874 0.4064)
			(stroke
				(width 0.1524)
				(type default)
			)
			(layer "B.SilkS")
		)
		(fp_line
			(start 0 0.381)
			(end 0 -0.381)
			(stroke
				(width 0.1524)
				(type default)
			)
			(layer "B.SilkS")
		)
		(fp_line
			(start 0.7874 0.4064)
			(end 0.7874 -0.4064)
			(stroke
				(width 0.1524)
				(type default)
			)
			(layer "B.SilkS")
		)
		(fp_line
			(start -0.7874 0.4064)
			(end 0.7874 0.4064)
			(stroke
				(width 0.1524)
				(type default)
			)
			(layer "B.SilkS")
		)
		(fp_poly
			(pts
				(xy 0.5334 0.254) (xy 0.635 0.254) (xy 0.635 0.2286) (xy 0.635 -0.254) (xy 0.5334 -0.254) (xy 0.5334 -0.2794)
				(xy -0.5334 -0.2794) (xy -0.5334 -0.254) (xy -0.635 -0.254) (xy -0.635 0.254) (xy -0.5334 0.254)
				(xy -0.5334 0.2794) (xy 0.508 0.2794) (xy 0.5334 0.2794)
			)
			(stroke
				(width 0)
				(type default)
			)
			(fill no)
			(layer "B.CrtYd")
		)
		(pad "1" smd rect
			(at -0.40005 0 270)
			(size 0.4572 0.508)
			(layers "B.Cu" "B.Mask" "B.Paste")
			(net "P1V05_LAN1")
		)
		(pad "2" smd rect
			(at 0.40005 0 270)
			(size 0.4572 0.508)
			(layers "B.Cu" "B.Mask" "B.Paste")
			(net "GND")
		)
	)
	(footprint ""
		(layer "B.Cu")
		(at 40.376602 -152.636982)
		(property "Reference" "C402"
			(at -6.359652 -10.195814 0)
			(unlocked yes)
			(layer "B.SilkS")
			(effects
				(font
					(size 0.7874 0.5842)
					(thickness 0.1524)
				)
				(justify left mirror)
			)
		)
		(property "Value" ""
			(at 0 0 0)
			(layer "B.Fab")
			(effects
				(font
					(size 1.27 1.27)
				)
				(justify mirror)
			)
		)
		(duplicate_pad_numbers_are_jumpers no)
		(fp_line
			(start -0.7874 -0.4064)
			(end -0.7874 0.4064)
			(stroke
				(width 0.1524)
				(type default)
			)
			(layer "B.SilkS")
		)
		(fp_line
			(start -0.7874 0.4064)
			(end 0.7874 0.4064)
			(stroke
				(width 0.1524)
				(type default)
			)
			(layer "B.SilkS")
		)
		(fp_line
			(start 0 0.381)
			(end 0 -0.381)
			(stroke
				(width 0.1524)
				(type default)
			)
			(layer "B.SilkS")
		)
		(fp_line
			(start 0.7874 -0.4064)
			(end -0.7874 -0.4064)
			(stroke
				(width 0.1524)
				(type default)
			)
			(layer "B.SilkS")
		)
		(fp_line
			(start 0.7874 0.4064)
			(end 0.7874 -0.4064)
			(stroke
				(width 0.1524)
				(type default)
			)
			(layer "B.SilkS")
		)
		(fp_poly
			(pts
				(xy 0.5334 0.254) (xy 0.635 0.254) (xy 0.635 0.2286) (xy 0.635 -0.254) (xy 0.5334 -0.254) (xy 0.5334 -0.2794)
				(xy -0.5334 -0.2794) (xy -0.5334 -0.254) (xy -0.635 -0.254) (xy -0.635 0.254) (xy -0.5334 0.254)
				(xy -0.5334 0.2794) (xy 0.508 0.2794) (xy 0.5334 0.2794)
			)
			(stroke
				(width 0)
				(type default)
			)
			(fill no)
			(layer "B.CrtYd")
		)
		(pad "1" smd rect
			(at -0.40005 0 180)
			(size 0.4572 0.508)
			(layers "B.Cu" "B.Mask" "B.Paste")
			(net "P1V9_LAN1")
		)
		(pad "2" smd rect
			(at 0.40005 0 180)
			(size 0.4572 0.508)
			(layers "B.Cu" "B.Mask" "B.Paste")
			(net "GND")
		)
	)
	(footprint ""
		(layer "B.Cu")
		(at 150.47976 -184.951624 -90)
		(property "Reference" "C720"
			(at -4.357624 3.18516 270)
			(unlocked yes)
			(layer "B.SilkS")
			(effects
				(font
					(size 0.7874 0.5842)
					(thickness 0.1524)
				)
				(justify left mirror)
			)
		)
		(property "Value" ""
			(at 0 0 90)
			(layer "B.Fab")
			(effects
				(font
					(size 1.27 1.27)
				)
				(justify mirror)
			)
		)
		(duplicate_pad_numbers_are_jumpers no)
		(fp_line
			(start -0.7874 0.4064)
			(end 0.7874 0.4064)
			(stroke
				(width 0.1524)
				(type default)
			)
			(layer "B.SilkS")
		)
		(fp_line
			(start 0.7874 0.4064)
			(end 0.7874 -0.4064)
			(stroke
				(width 0.1524)
				(type default)
			)
			(layer "B.SilkS")
		)
		(fp_line
			(start 0 0.381)
			(end 0 -0.381)
			(stroke
				(width 0.1524)
				(type default)
			)
			(layer "B.SilkS")
		)
		(fp_line
			(start -0.7874 -0.4064)
			(end -0.7874 0.4064)
			(stroke
				(width 0.1524)
				(type default)
			)
			(layer "B.SilkS")
		)
		(fp_line
			(start 0.7874 -0.4064)
			(end -0.7874 -0.4064)
			(stroke
				(width 0.1524)
				(type default)
			)
			(layer "B.SilkS")
		)
		(fp_poly
			(pts
				(xy 0.5334 0.254) (xy 0.635 0.254) (xy 0.635 0.2286) (xy 0.635 -0.254) (xy 0.5334 -0.254) (xy 0.5334 -0.2794)
				(xy -0.5334 -0.2794) (xy -0.5334 -0.254) (xy -0.635 -0.254) (xy -0.635 0.254) (xy -0.5334 0.254)
				(xy -0.5334 0.2794) (xy 0.508 0.2794) (xy 0.5334 0.2794)
			)
			(stroke
				(width 0)
				(type default)
			)
			(fill no)
			(layer "B.CrtYd")
		)
		(pad "1" smd rect
			(at -0.40005 0 90)
			(size 0.4572 0.508)
			(layers "B.Cu" "B.Mask" "B.Paste")
			(net "UART_T11_NODE1_RXD")
		)
		(pad "2" smd rect
			(at 0.40005 0 90)
			(size 0.4572 0.508)
			(layers "B.Cu" "B.Mask" "B.Paste")
			(net "GND")
		)
	)
)
